FILE_TYPE = MACRO_DRAWING;
SET COLOR_WIRE YELLOW;
SET COLOR_PROP ORANGE;
SET COLOR_DOT WHITE;
SET COLOR_ARC YELLOW;
SET COLOR_BODY GREEN;
SET COLOR_NOTE PURPLE;
SET PROP_DISPLAY VALUE;
SET PAGE_NUMBER P467;
FORCEADD UNIVERSAL_GND..1
(-6075 3775);
FORCEPROP 3 LASTPIN (-6075 3825) SIG_NAME GND\g
J 0
(-6065 3835);
DISPLAY 0.659574 (-6065 3835);
PAINT MONO (-6065 3835);
DISPLAY INVISIBLE (-6065 3835);
FORCEPROP 2 LAST CDS_LIB pure_quanta_power
J 0
(-6075 3775);
DISPLAY INVISIBLE (-6075 3775);
FORCEPROP 2 LAST BOM_COST OCP3.0 
J 0
(-6275 3850);
DISPLAY 0.680851 (-6275 3850);
DISPLAY INVISIBLE (-6275 3850);
FORCEPROP 1 LAST HDL_POWER GND
J 1
(-6050 3700);
DISPLAY 0.872340 (-6050 3700);
PAINT GREEN (-6050 3700);
DISPLAY INVISIBLE (-6050 3700);
FORCEPROP 1 LAST PATH I1
J 0
(-6000 3775);
DISPLAY 0.872340 (-6000 3775);
PAINT AQUA (-6000 3775);
DISPLAY INVISIBLE (-6000 3775);
FORCEADD UNIVERSAL_POWER..1
(-6075 5725);
FORCEPROP 3 LASTPIN (-6075 5675) SIG_NAME P1V8_AUX\g
J 0
(-6065 5685);
DISPLAY 0.659574 (-6065 5685);
PAINT MONO (-6065 5685);
DISPLAY INVISIBLE (-6065 5685);
FORCEPROP 1 LAST HDL_POWER P1V8_AUX
J 1
(-6075 5775);
DISPLAY 0.489362 (-6075 5775);
PAINT GREEN (-6075 5775);
FORCEPROP 2 LAST CDS_LIB pure_quanta_power
J 0
(-6075 5725);
DISPLAY INVISIBLE (-6075 5725);
FORCEPROP 1 LAST PATH I10
J 0
(-6025 5750);
DISPLAY 0.872340 (-6025 5750);
PAINT AQUA (-6025 5750);
DISPLAY INVISIBLE (-6025 5750);
FORCEADD OFFPAGE..2
(-4425 4650);
FORCEPROP 2 LAST $XR0 82 
J 0
(-4236 4650);
DISPLAY 0.638298 (-4236 4650);
PAINT MONO (-4236 4650);
FORCEPROP 2 LAST CDS_LIB standard
J 0
(-4425 4650);
DISPLAY INVISIBLE (-4425 4650);
FORCEPROP 1 LAST OFFPAGE TRUE
J 0
(-4100 4525);
DISPLAY 0.872340 (-4100 4525);
PAINT GREEN (-4100 4525);
DISPLAY INVISIBLE (-4100 4525);
FORCEPROP 1 LAST COMMENT_BODY TRUE
J 0
(-4470 4555);
DISPLAY 0.872340 (-4470 4555);
PAINT GREEN (-4470 4555);
DISPLAY INVISIBLE (-4470 4555);
FORCEPROP 2 LAST PATH I12
J 0
(-4225 4700);
DISPLAY 0.680851 (-4225 4700);
DISPLAY INVISIBLE (-4225 4700);
FORCEADD OFFPAGE..2
(-4425 4725);
FORCEPROP 2 LAST $XR0 82 
J 0
(-4236 4725);
DISPLAY 0.638298 (-4236 4725);
PAINT MONO (-4236 4725);
FORCEPROP 2 LAST CDS_LIB standard
J 0
(-4425 4725);
DISPLAY INVISIBLE (-4425 4725);
FORCEPROP 1 LAST OFFPAGE TRUE
J 0
(-4100 4600);
DISPLAY 0.872340 (-4100 4600);
PAINT GREEN (-4100 4600);
DISPLAY INVISIBLE (-4100 4600);
FORCEPROP 1 LAST COMMENT_BODY TRUE
J 0
(-4470 4630);
DISPLAY 0.872340 (-4470 4630);
PAINT GREEN (-4470 4630);
DISPLAY INVISIBLE (-4470 4630);
FORCEPROP 2 LAST PATH I13
J 0
(-4225 4775);
DISPLAY 0.680851 (-4225 4775);
DISPLAY INVISIBLE (-4225 4775);
FORCEADD Q_RES..2
(-6075 4250);
FORCEPROP 1 LAST LOCATION R6744
J 0
(-6030 4375);
DISPLAY 0.978723 (-6030 4375);
FORCEPROP 0 LAST $SEC 1
J 0
(-6025 4425);
DISPLAY 0.680851 (-6025 4425);
PAINT MONO (-6025 4425);
DISPLAY INVISIBLE (-6025 4425);
FORCEPROP 0 LAST CDS_SEC 1
J 0
(-6025 4425);
DISPLAY 0.680851 (-6025 4425);
DISPLAY INVISIBLE (-6025 4425);
FORCEPROP 1 LASTPIN (-6075 4350) $PN 1
J 0
(-6070 4312);
DISPLAY 0.787234 (-6070 4312);
PAINT MONO (-6070 4312);
FORCEPROP 1 LASTPIN (-6075 4150) $PN 2
J 0
(-6070 4160);
DISPLAY 0.787234 (-6070 4160);
PAINT MONO (-6070 4160);
FORCEPROP 1 LAST VALUE 1K
J 0
(-6030 4325);
DISPLAY 0.978723 (-6030 4325);
FORCEPROP 1 LAST TOLERANCE 1%
J 0
(-6030 4275);
DISPLAY 0.978723 (-6030 4275);
FORCEPROP 1 LAST PACK_TYPE 0402LF
J 0
(-6025 4125);
DISPLAY 0.978723 (-6025 4125);
FORCEPROP 1 LAST MATERIAL CHIP
J 0
(-6035 4175);
DISPLAY 0.978723 (-6035 4175);
FORCEPROP 1 LAST WATTAGE 1/16W
J 0
(-6035 4225);
DISPLAY 0.978723 (-6035 4225);
FORCEPROP 2 LAST CDS_LIB pure_quanta
J 0
(-6075 4250);
DISPLAY INVISIBLE (-6075 4250);
FORCEPROP 1 LAST PATH I2
J 0
(-6025 4425);
DISPLAY 0.978723 (-6025 4425);
PAINT WHITE (-6025 4425);
DISPLAY INVISIBLE (-6025 4425);
FORCEPROP 1 LAST PART_NUMBER CS21002FB06
J 0
(-6035 4125);
DISPLAY 0.978723 (-6035 4125);
DISPLAY INVISIBLE (-6035 4125);
FORCEADD UNIVERSAL_GND..1
(-5725 3775);
FORCEPROP 3 LASTPIN (-5725 3825) SIG_NAME GND\g
J 0
(-5715 3835);
DISPLAY 0.659574 (-5715 3835);
PAINT MONO (-5715 3835);
DISPLAY INVISIBLE (-5715 3835);
FORCEPROP 2 LAST CDS_LIB pure_quanta_power
J 0
(-5725 3775);
DISPLAY INVISIBLE (-5725 3775);
FORCEPROP 2 LAST BOM_COST OCP3.0 
J 0
(-5925 3850);
DISPLAY 0.680851 (-5925 3850);
DISPLAY INVISIBLE (-5925 3850);
FORCEPROP 1 LAST HDL_POWER GND
J 1
(-5700 3700);
DISPLAY 0.872340 (-5700 3700);
PAINT GREEN (-5700 3700);
DISPLAY INVISIBLE (-5700 3700);
FORCEPROP 1 LAST PATH I3
J 0
(-5650 3775);
DISPLAY 0.872340 (-5650 3775);
PAINT AQUA (-5650 3775);
DISPLAY INVISIBLE (-5650 3775);
FORCEADD Q_RES..2
(-5725 4250);
FORCEPROP 1 LAST LOCATION R6745
J 0
(-5680 4375);
DISPLAY 0.978723 (-5680 4375);
FORCEPROP 0 LAST $SEC 1
J 0
(-5675 4425);
DISPLAY 0.680851 (-5675 4425);
PAINT MONO (-5675 4425);
DISPLAY INVISIBLE (-5675 4425);
FORCEPROP 0 LAST CDS_SEC 1
J 0
(-5675 4425);
DISPLAY 0.680851 (-5675 4425);
DISPLAY INVISIBLE (-5675 4425);
FORCEPROP 1 LASTPIN (-5725 4350) $PN 1
J 0
(-5720 4312);
DISPLAY 0.787234 (-5720 4312);
PAINT MONO (-5720 4312);
FORCEPROP 1 LASTPIN (-5725 4150) $PN 2
J 0
(-5720 4160);
DISPLAY 0.787234 (-5720 4160);
PAINT MONO (-5720 4160);
FORCEPROP 1 LAST PACK_TYPE 0402LF
J 0
(-5675 4125);
DISPLAY 0.978723 (-5675 4125);
FORCEPROP 1 LAST MATERIAL CHIP
J 0
(-5685 4175);
DISPLAY 0.978723 (-5685 4175);
FORCEPROP 1 LAST WATTAGE 1/16W
J 0
(-5685 4225);
DISPLAY 0.978723 (-5685 4225);
FORCEPROP 1 LAST TOLERANCE 1%
J 0
(-5680 4275);
DISPLAY 0.978723 (-5680 4275);
FORCEPROP 1 LAST VALUE 1K
J 0
(-5680 4325);
DISPLAY 0.978723 (-5680 4325);
FORCEPROP 2 LAST CDS_LIB pure_quanta
J 0
(-5725 4250);
DISPLAY INVISIBLE (-5725 4250);
FORCEPROP 1 LAST PATH I4
J 0
(-5675 4425);
DISPLAY 0.978723 (-5675 4425);
PAINT WHITE (-5675 4425);
DISPLAY INVISIBLE (-5675 4425);
FORCEPROP 1 LAST PART_NUMBER CS21002FB06
J 0
(-5685 4125);
DISPLAY 0.978723 (-5685 4125);
DISPLAY INVISIBLE (-5685 4125);
FORCEADD Q_RES..2
(-6075 5200);
FORCEPROP 1 LAST LOCATION R6742
J 0
(-6030 5325);
DISPLAY 0.978723 (-6030 5325);
FORCEPROP 0 LAST $SEC 1
J 0
(-6025 5375);
DISPLAY 0.680851 (-6025 5375);
PAINT MONO (-6025 5375);
DISPLAY INVISIBLE (-6025 5375);
FORCEPROP 0 LAST CDS_SEC 1
J 0
(-6025 5375);
DISPLAY 0.680851 (-6025 5375);
DISPLAY INVISIBLE (-6025 5375);
FORCEPROP 1 LASTPIN (-6075 5300) $PN 1
J 0
(-6070 5262);
DISPLAY 0.787234 (-6070 5262);
PAINT MONO (-6070 5262);
FORCEPROP 1 LASTPIN (-6075 5100) $PN 2
J 0
(-6070 5110);
DISPLAY 0.787234 (-6070 5110);
PAINT MONO (-6070 5110);
FORCEPROP 1 LAST VALUE 1K
J 0
(-6030 5275);
DISPLAY 0.978723 (-6030 5275);
FORCEPROP 1 LAST TOLERANCE 1%
J 0
(-6030 5225);
DISPLAY 0.978723 (-6030 5225);
FORCEPROP 1 LAST WATTAGE 1/16W
J 0
(-6035 5175);
DISPLAY 0.978723 (-6035 5175);
FORCEPROP 1 LAST PACK_TYPE 0402LF
J 0
(-6025 5075);
DISPLAY 0.978723 (-6025 5075);
FORCEPROP 1 LAST MATERIAL EMPTY
J 0
(-6035 5125);
DISPLAY 0.978723 (-6035 5125);
FORCEPROP 2 LAST CDS_LIB pure_quanta
J 0
(-6075 5200);
DISPLAY INVISIBLE (-6075 5200);
FORCEPROP 1 LAST PATH I5
J 0
(-6025 5375);
DISPLAY 0.978723 (-6025 5375);
PAINT WHITE (-6025 5375);
DISPLAY INVISIBLE (-6025 5375);
FORCEPROP 1 LAST PART_NUMBER CS21002FB06
J 0
(-6035 5075);
DISPLAY 0.978723 (-6035 5075);
DISPLAY INVISIBLE (-6035 5075);
FORCEADD Q_RES..2
(-5725 5200);
FORCEPROP 1 LAST LOCATION R6743
J 0
(-5680 5325);
DISPLAY 0.978723 (-5680 5325);
FORCEPROP 0 LAST $SEC 1
J 0
(-5675 5375);
DISPLAY 0.680851 (-5675 5375);
PAINT MONO (-5675 5375);
DISPLAY INVISIBLE (-5675 5375);
FORCEPROP 0 LAST CDS_SEC 1
J 0
(-5675 5375);
DISPLAY 0.680851 (-5675 5375);
DISPLAY INVISIBLE (-5675 5375);
FORCEPROP 1 LASTPIN (-5725 5300) $PN 1
J 0
(-5720 5262);
DISPLAY 0.787234 (-5720 5262);
PAINT MONO (-5720 5262);
FORCEPROP 1 LASTPIN (-5725 5100) $PN 2
J 0
(-5720 5110);
DISPLAY 0.787234 (-5720 5110);
PAINT MONO (-5720 5110);
FORCEPROP 1 LAST VALUE 1K
J 0
(-5680 5275);
DISPLAY 0.978723 (-5680 5275);
FORCEPROP 1 LAST MATERIAL EMPTY
J 0
(-5685 5125);
DISPLAY 0.978723 (-5685 5125);
FORCEPROP 1 LAST WATTAGE 1/16W
J 0
(-5685 5175);
DISPLAY 0.978723 (-5685 5175);
FORCEPROP 1 LAST TOLERANCE 1%
J 0
(-5680 5225);
DISPLAY 0.978723 (-5680 5225);
FORCEPROP 1 LAST PACK_TYPE 0402LF
J 0
(-5675 5075);
DISPLAY 0.978723 (-5675 5075);
FORCEPROP 2 LAST CDS_LIB pure_quanta
J 0
(-5725 5200);
DISPLAY INVISIBLE (-5725 5200);
FORCEPROP 1 LAST PATH I6
J 0
(-5675 5375);
DISPLAY 0.978723 (-5675 5375);
PAINT WHITE (-5675 5375);
DISPLAY INVISIBLE (-5675 5375);
FORCEPROP 1 LAST PART_NUMBER CS21002FB06
J 0
(-5685 5075);
DISPLAY 0.978723 (-5685 5075);
DISPLAY INVISIBLE (-5685 5075);
FORCEADD DNS..2
(-6125 5150);
PAINT RED (-6125 5150);
FORCEPROP 2 LAST CDS_LIB mstr_misc
J 0
(-6125 5150);
DISPLAY INVISIBLE (-6125 5150);
FORCEPROP 1 LAST COMMENT_BODY TRUE
R 1
J 0
(-6050 4925);
DISPLAY 0.872340 (-6050 4925);
PAINT GREEN (-6050 4925);
DISPLAY INVISIBLE (-6050 4925);
FORCEADD DNS..2
(-5725 5175);
PAINT RED (-5725 5175);
FORCEPROP 2 LAST CDS_LIB mstr_misc
J 0
(-5725 5175);
DISPLAY INVISIBLE (-5725 5175);
FORCEPROP 1 LAST COMMENT_BODY TRUE
R 1
J 0
(-5650 4950);
DISPLAY 0.872340 (-5650 4950);
PAINT GREEN (-5650 4950);
DISPLAY INVISIBLE (-5650 4950);
FORCEADD QUANTA_TITLE_BLOCK_C..1
(0 0);
FORCEPROP 0 LAST CDS_CON_LAST_MODIFIED Thu Sep 14 16:13:04 2023
J 0
(-1885 15);
DISPLAY INVISIBLE (-1885 15);
FORCEPROP 1 LAST CUSTOM_TXT_CDS <CON_LAST_MODIFIED>
J 0
(-1885 15);
DISPLAY 0.978723 (-1885 15);
FORCEPROP 2 LAST CUSTOM_TXT_CDS <XR_PAGE_TITLE>
J 0
(-7890 5250);
DISPLAY 0.638298 (-7890 5250);
PAINT PINK (-7890 5250);
DISPLAY INVISIBLE (-7890 5250);
FORCEPROP 1 LAST CUSTOM_TXT_CDS <NAME_2>
J 0
(-3175 50);
FORCEPROP 1 LAST CUSTOM_TXT_CDS <NAME_1>
J 0
(-3175 175);
FORCEPROP 1 LAST CUSTOM_TXT_CDS <Q_NUMBER>
J 0
(-1403 103);
DISPLAY 1.212766 (-1403 103);
FORCEPROP 1 LAST CUSTOM_TXT_CDS <Q_PROJ>
J 0
(-2382 102);
DISPLAY 1.212766 (-2382 102);
FORCEPROP 1 LAST CUSTOM_TXT_CDS <Q_REV>
J 0
(-184 103);
DISPLAY 1.212766 (-184 103);
FORCEPROP 1 LAST CUSTOM_TXT_CDS <CON_PAGE_NUM> OF <CON_TOTAL_PAGES>
J 0
(-446 18);
DISPLAY 0.978723 (-446 18);
FORCEPROP 1 LAST Q_TITLE BOARD ID (RETIMER)
J 0
(-9366 26);
DISPLAY 2.446809 (-9366 26);
PAINT GREEN (-9366 26);
FORCEPROP 2 LAST CDS_LIB pure_quanta
J 0
(0 0);
DISPLAY INVISIBLE (0 0);
FORCEPROP 1 LAST CDS_LMAN_SYM_OUTLINE -9475,6775,100,-125
J 0
(0 0);
DISPLAY 0.468085 (0 0);
PAINT GREEN (0 0);
DISPLAY INVISIBLE (0 0);
FORCEPROP 2 LAST PAGE_BORDER TRUE
J 0
(-7890 5250);
DISPLAY 0.638298 (-7890 5250);
PAINT PINK (-7890 5250);
DISPLAY INVISIBLE (-7890 5250);
FORCEPROP 2 LAST CDS_XR_PAGE_TITLE CR-359 : @T6G_MB_LIB.T6G(SCH_1):PAGE359
J 0
(-7890 5250);
DISPLAY 0.638298 (-7890 5250);
PAINT PINK (-7890 5250);
DISPLAY INVISIBLE (-7890 5250);
FORCEPROP 1 LAST Q_DEPT BU9
J 1
(-3763 49);
DISPLAY 1.957447 (-3763 49);
PAINT GREEN (-3763 49);
DISPLAY INVISIBLE (-3763 49);
FORCEPROP 1 LAST COMMENT_BODY TRUE
J 0
(12 -13);
DISPLAY 0.978723 (12 -13);
PAINT GREEN (12 -13);
DISPLAY INVISIBLE (12 -13);
WIRE 16 -1 (-6075 3825)(-6075 4150);
WIRE 16 -1 (-5725 4150)(-5725 3825);
WIRE 16 -1 (-6075 5675)(-6075 5500);
WIRE 16 -1 (-6075 5500)(-5725 5500);
WIRE 16 -1 (-6075 5500)(-6075 5300);
WIRE 16 -1 (-5725 5300)(-5725 5500);
WIRE 16 -1 (-5725 4350)(-5725 4650);
WIRE 16 -1 (-5725 4650)(-4475 4650);
FORCEPROP 2 LAST SIG_NAME RT_BOARD_ID_ID0
J 0
(-5200 4660);
DISPLAY 0.680851 (-5200 4660);
WIRE 16 -1 (-5725 5100)(-5725 4650);
WIRE 16 -1 (-6075 4350)(-6075 4725);
WIRE 16 -1 (-4475 4725)(-6075 4725);
FORCEPROP 2 LAST SIG_NAME RT_BOARD_ID_ID1
J 0
(-5210 4735);
DISPLAY 0.680851 (-5210 4735);
WIRE 16 -1 (-6075 4725)(-6075 5100);
WIRE 16 -1 (-6700 5800)(-7000 5800);
WIRE 16 -1 (-6700 5800)(-6700 5625);
WIRE 16 -1 (-7000 5800)(-7000 4750);
WIRE 16 -1 (-7000 5800)(-7350 5800);
WIRE 16 -1 (-7350 5800)(-8075 5800);
WIRE 16 -1 (-7350 5800)(-7350 4750);
WIRE 16 -1 (-6700 4750)(-7000 4750);
WIRE 16 -1 (-7000 4750)(-7350 4750);
WIRE 16 -1 (-6700 5625)(-6700 5425);
WIRE 16 -1 (-8075 5625)(-6700 5625);
WIRE 16 -1 (-8075 5625)(-8075 5800);
WIRE 16 -1 (-8075 5625)(-8075 5425);
WIRE 16 -1 (-6700 5425)(-6700 5225);
WIRE 16 -1 (-8075 5425)(-6700 5425);
WIRE 16 -1 (-7350 4750)(-8075 4750);
WIRE 16 -1 (-6700 5025)(-6700 4750);
WIRE 16 -1 (-6700 5225)(-6700 5025);
WIRE 16 -1 (-8075 5025)(-6700 5025);
WIRE 16 -1 (-8075 4750)(-8075 5025);
WIRE 16 -1 (-8075 5425)(-8075 5225);
WIRE 16 -1 (-8075 5225)(-6700 5225);
WIRE 16 -1 (-8075 5225)(-8075 5025);
DOT 1 (-5725 4650);
DOT 1 (-6075 5500);
DOT 1 (-6075 4725);
DOT 1 (-8075 5225);
DOT 1 (-7350 5800);
DOT 1 (-7000 5800);
DOT 1 (-6700 5625);
DOT 1 (-6700 5425);
DOT 1 (-6700 5225);
DOT 1 (-6700 5025);
DOT 1 (-8075 5425);
DOT 1 (-8075 5625);
DOT 1 (-8075 5025);
DOT 1 (-7000 4750);
DOT 1 (-7350 4750);
FORCENOTE
0
(-6850 5100) 0;
DISPLAY LEFT (-6850 5100);
DISPLAY 1.021277 (-6850 5100);
PAINT WHITE (-6850 5100);
FORCENOTE
1
(-6850 4875) 0;
DISPLAY LEFT (-6850 4875);
DISPLAY 1.021277 (-6850 4875);
PAINT WHITE (-6850 4875);
FORCENOTE
RSVD
(-7975 4850) 0;
DISPLAY LEFT (-7975 4850);
DISPLAY 1.021277 (-7975 4850);
PAINT WHITE (-7975 4850);
FORCENOTE
1
(-6850 5300) 0;
DISPLAY LEFT (-6850 5300);
DISPLAY 1.021277 (-6850 5300);
PAINT WHITE (-6850 5300);
FORCENOTE
0
(-7200 5300) 0;
DISPLAY LEFT (-7200 5300);
DISPLAY 1.021277 (-7200 5300);
PAINT WHITE (-7200 5300);
FORCENOTE
RENESAS
(-7975 5100) 0;
DISPLAY LEFT (-7975 5100);
DISPLAY 1.021277 (-7975 5100);
PAINT WHITE (-7975 5100);
FORCENOTE
PARADE
(-7975 5300) 0;
DISPLAY LEFT (-7975 5300);
DISPLAY 1.021277 (-7975 5300);
PAINT WHITE (-7975 5300);
FORCENOTE
BOARD ID(RT)
(-8000 5700) 0;
DISPLAY LEFT (-8000 5700);
DISPLAY 1.021277 (-8000 5700);
PAINT WHITE (-8000 5700);
FORCENOTE
ASTERA_LABS
(-7975 5475) 0;
DISPLAY LEFT (-7975 5475);
DISPLAY 1.021277 (-7975 5475);
PAINT WHITE (-7975 5475);
FORCENOTE
1
(-7200 5100) 0;
DISPLAY LEFT (-7200 5100);
DISPLAY 1.021277 (-7200 5100);
PAINT WHITE (-7200 5100);
FORCENOTE
ID1
(-7250 5700) 0;
DISPLAY LEFT (-7250 5700);
DISPLAY 1.021277 (-7250 5700);
PAINT WHITE (-7250 5700);
FORCENOTE
ID0
(-6925 5700) 0;
DISPLAY LEFT (-6925 5700);
DISPLAY 1.021277 (-6925 5700);
PAINT WHITE (-6925 5700);
FORCENOTE
1
(-7200 4850) 0;
DISPLAY LEFT (-7200 4850);
DISPLAY 1.021277 (-7200 4850);
PAINT WHITE (-7200 4850);
FORCENOTE
0
(-6850 5500) 0;
DISPLAY LEFT (-6850 5500);
DISPLAY 1.021277 (-6850 5500);
PAINT WHITE (-6850 5500);
FORCENOTE
0
(-7200 5500) 0;
DISPLAY LEFT (-7200 5500);
DISPLAY 1.021277 (-7200 5500);
PAINT WHITE (-7200 5500);
QUIT
